#ISCELL
  pure_quanta quanta_title_block_c *
  *
#ISCELL
  logical_power universal_gnd *
  page73_i1
#CELL
  pure_quanta socket4677_azif0045p001c01cs *
  page73_i2
#ISCELL
  logical_power universal_gnd *
  page73_i3
#ISCELL
  logical_power universal_gnd *
  page73_i4
#CELL
  pure_quanta socket4677_azif0045p001c01cs *
  page73_i5
#ISCELL
  logical_power universal_gnd *
  page73_i6
#ISCELL
  logical_power universal_gnd *
  page73_i7
#CELL
  pure_quanta socket4677_azif0045p001c01cs *
  page73_i8
